(kicad_pcb
	(version 20260206)
	(generator "pcbnew")
	(generator_version "10.0")
	(general
		(thickness 1.6)
		(legacy_teardrops no)
	)
	(paper "A4")
	(title_block
		(title "Bryce Canyon_IOM_IOC_16318-2_OCP.brd")
		(comment 1 "Bryce Canyon / footprints 241-241 of 1605")
	)
	(layers
		(0 "F.Cu" signal "TOP")
		(4 "In1.Cu" signal "L2GND")
		(6 "In2.Cu" signal "L3")
		(8 "In3.Cu" signal "L4VCC")
		(10 "In4.Cu" signal "L5VCC")
		(12 "In5.Cu" signal "L6")
		(14 "In6.Cu" signal "L7GND")
		(2 "B.Cu" signal "BOTTOM")
		(9 "F.Adhes" user "F.Adhesive")
		(11 "B.Adhes" user "B.Adhesive")
		(13 "F.Paste" user "Package Geometry/Pastemask Top")
		(15 "B.Paste" user "Package Geometry/Pastemask Bottom")
		(5 "F.SilkS" user "Ref Des/Silkscreen Top")
		(7 "B.SilkS" user "Ref Des/Silkscreen Bottom")
		(1 "F.Mask" user "Board Geometry/Soldermask Top")
		(3 "B.Mask" user "Board Geometry/Soldermask Bottom")
		(17 "Dwgs.User" user "User.Drawings")
		(19 "Cmts.User" user "User.Comments")
		(21 "Eco1.User" user "User.Eco1")
		(23 "Eco2.User" user "User.Eco2")
		(25 "Edge.Cuts" user "Board Geometry/Outline")
		(27 "Margin" user)
		(31 "F.CrtYd" user "Package Geometry/Place Bound Top")
		(29 "B.CrtYd" user "Package Geometry/Place Bound Bottom")
		(35 "F.Fab" user "Ref Des/Assembly Top")
		(33 "B.Fab" user "Ref Des/Assembly Bottom")
	)
	(footprint ""
		(layer "F.Cu")
		(at 20.034504 -142.561564)
		(property "Reference" "U28"
			(at 0 0 0)
			(layer "F.SilkS")
			(hide yes)
			(effects
				(font
					(size 1.27 1.27)
				)
			)
		)
		(property "Value" "H5AN4G6NAFR-TFC-GP"
			(at -8.423656 -15.9766 0)
			(unlocked yes)
			(layer "F.Fab")
			(hide yes)
			(effects
				(font
					(size 1.016 1.016)
					(thickness 0.1524)
				)
			)
		)
		(property "Device Type" "BGA96D075130H48"
			(at -8.423656 -17.5006 0)
			(unlocked yes)
			(layer "F.Fab")
			(hide yes)
			(effects
				(font
					(size 1.016 1.016)
					(thickness 0.1524)
				)
			)
		)
		(duplicate_pad_numbers_are_jumpers no)
		(fp_line
			(start -4.080256 -6.830314)
			(end -2.480056 -6.830314)
			(stroke
				(width 0.508)
				(type default)
			)
			(layer "F.SilkS")
		)
		(fp_line
			(start -4.080256 -5.230114)
			(end -4.080256 -6.830314)
			(stroke
				(width 0.508)
				(type default)
			)
			(layer "F.SilkS")
		)
		(fp_line
			(start -3.750056 -6.500114)
			(end -3.750056 6.500114)
			(stroke
				(width 0.1524)
				(type default)
			)
			(layer "F.SilkS")
		)
		(fp_line
			(start -3.750056 6.500114)
			(end 3.750056 6.500114)
			(stroke
				(width 0.1524)
				(type default)
			)
			(layer "F.SilkS")
		)
		(fp_line
			(start 3.750056 -6.500114)
			(end -3.750056 -6.500114)
			(stroke
				(width 0.1524)
				(type default)
			)
			(layer "F.SilkS")
		)
		(fp_line
			(start 3.750056 6.500114)
			(end 3.750056 -6.500114)
			(stroke
				(width 0.1524)
				(type default)
			)
			(layer "F.SilkS")
		)
		(fp_rect
			(start -3.750056 6.500114)
			(end 3.750056 -6.500114)
			(stroke
				(width 0)
				(type default)
			)
			(fill no)
			(layer "F.CrtYd")
		)
		(fp_poly
			(pts
				(xy -4.7498 7.5057) (xy -4.7498 -7.5057) (xy 4.7498 -7.5057) (xy 4.7498 -0.54864) (xy 3.750056 -0.54864)
				(xy 3.750056 -6.500114) (xy -3.750056 -6.500114) (xy -3.750056 6.500114) (xy 3.750056 6.500114)
				(xy 3.750056 -0.54356) (xy 4.7498 -0.54356) (xy 4.7498 7.5057)
			)
			(stroke
				(width 0)
				(type default)
			)
			(fill no)
			(layer "F.CrtYd")
		)
		(fp_rect
			(start -5.750052 8.50011)
			(end 5.750052 -8.50011)
			(stroke
				(width 0)
				(type default)
			)
			(fill no)
			(layer "F.Fab")
		)
		(pad "A1" smd circle
			(at -3.199892 -5.999988)
			(size 0.3556 0.3556)
			(layers "F.Cu" "F.Mask" "F.Paste")
			(net "P1V2_STBY")
		)
		(pad "A2" smd circle
			(at -2.400046 -5.999988)
			(size 0.3556 0.3556)
			(layers "F.Cu" "F.Mask" "F.Paste")
			(net "GND")
		)
		(pad "A3" smd circle
			(at -1.599946 -5.999988)
			(size 0.3556 0.3556)
			(layers "F.Cu" "F.Mask" "F.Paste")
			(net "MEMDQ_8")
		)
		(pad "A7" smd circle
			(at 1.599946 -5.999988)
			(size 0.3556 0.3556)
			(layers "F.Cu" "F.Mask" "F.Paste")
			(net "MEMDQS_N1")
		)
		(pad "A8" smd circle
			(at 2.400046 -5.999988)
			(size 0.3556 0.3556)
			(layers "F.Cu" "F.Mask" "F.Paste")
			(net "GND")
		)
		(pad "A9" smd circle
			(at 3.199892 -5.999988)
			(size 0.3556 0.3556)
			(layers "F.Cu" "F.Mask" "F.Paste")
			(net "P1V2_STBY")
		)
		(pad "B1" smd circle
			(at -3.199892 -5.199888)
			(size 0.3556 0.3556)
			(layers "F.Cu" "F.Mask" "F.Paste")
			(net "P2V5_STBY")
		)
		(pad "B2" smd circle
			(at -2.400046 -5.199888)
			(size 0.3556 0.3556)
			(layers "F.Cu" "F.Mask" "F.Paste")
			(net "GND")
		)
		(pad "B3" smd circle
			(at -1.599946 -5.199888)
			(size 0.3556 0.3556)
			(layers "F.Cu" "F.Mask" "F.Paste")
			(net "P1V2_STBY")
		)
		(pad "B7" smd circle
			(at 1.599946 -5.199888)
			(size 0.3556 0.3556)
			(layers "F.Cu" "F.Mask" "F.Paste")
			(net "MEMDQS_P1")
		)
		(pad "B8" smd circle
			(at 2.400046 -5.199888)
			(size 0.3556 0.3556)
			(layers "F.Cu" "F.Mask" "F.Paste")
			(net "MEMDQ_9")
		)
		(pad "B9" smd circle
			(at 3.199892 -5.199888)
			(size 0.3556 0.3556)
			(layers "F.Cu" "F.Mask" "F.Paste")
			(net "P1V2_STBY")
		)
		(pad "C1" smd circle
			(at -3.199892 -4.400042)
			(size 0.3556 0.3556)
			(layers "F.Cu" "F.Mask" "F.Paste")
			(net "P1V2_STBY")
		)
		(pad "C2" smd circle
			(at -2.400046 -4.400042)
			(size 0.3556 0.3556)
			(layers "F.Cu" "F.Mask" "F.Paste")
			(net "MEMDQ_12")
		)
		(pad "C3" smd circle
			(at -1.599946 -4.400042)
			(size 0.3556 0.3556)
			(layers "F.Cu" "F.Mask" "F.Paste")
			(net "MEMDQ_10")
		)
		(pad "C7" smd circle
			(at 1.599946 -4.400042)
			(size 0.3556 0.3556)
			(layers "F.Cu" "F.Mask" "F.Paste")
			(net "MEMDQ_11")
		)
		(pad "C8" smd circle
			(at 2.400046 -4.400042)
			(size 0.3556 0.3556)
			(layers "F.Cu" "F.Mask" "F.Paste")
			(net "MEMDQ_13")
		)
		(pad "C9" smd circle
			(at 3.199892 -4.400042)
			(size 0.3556 0.3556)
			(layers "F.Cu" "F.Mask" "F.Paste")
			(net "GND")
		)
		(pad "D1" smd circle
			(at -3.199892 -3.599942)
			(size 0.3556 0.3556)
			(layers "F.Cu" "F.Mask" "F.Paste")
			(net "P1V2_STBY")
		)
		(pad "D2" smd circle
			(at -2.400046 -3.599942)
			(size 0.3556 0.3556)
			(layers "F.Cu" "F.Mask" "F.Paste")
			(net "GND")
		)
		(pad "D3" smd circle
			(at -1.599946 -3.599942)
			(size 0.3556 0.3556)
			(layers "F.Cu" "F.Mask" "F.Paste")
			(net "MEMDQ_14")
		)
		(pad "D7" smd circle
			(at 1.599946 -3.599942)
			(size 0.3556 0.3556)
			(layers "F.Cu" "F.Mask" "F.Paste")
			(net "MEMDQ_15")
		)
		(pad "D8" smd circle
			(at 2.400046 -3.599942)
			(size 0.3556 0.3556)
			(layers "F.Cu" "F.Mask" "F.Paste")
			(net "GND")
		)
		(pad "D9" smd circle
			(at 3.199892 -3.599942)
			(size 0.3556 0.3556)
			(layers "F.Cu" "F.Mask" "F.Paste")
			(net "P1V2_STBY")
		)
		(pad "E1" smd circle
			(at -3.199892 -2.800096)
			(size 0.3556 0.3556)
			(layers "F.Cu" "F.Mask" "F.Paste")
			(net "GND")
		)
		(pad "E2" smd circle
			(at -2.400046 -2.800096)
			(size 0.3556 0.3556)
			(layers "F.Cu" "F.Mask" "F.Paste")
			(net "MEMDM_1")
		)
		(pad "E3" smd circle
			(at -1.599946 -2.800096)
			(size 0.3556 0.3556)
			(layers "F.Cu" "F.Mask" "F.Paste")
			(net "GND")
		)
		(pad "E7" smd circle
			(at 1.599946 -2.800096)
			(size 0.3556 0.3556)
			(layers "F.Cu" "F.Mask" "F.Paste")
			(net "MEMDM_0")
		)
		(pad "E8" smd circle
			(at 2.400046 -2.800096)
			(size 0.3556 0.3556)
			(layers "F.Cu" "F.Mask" "F.Paste")
			(net "GND")
		)
		(pad "E9" smd circle
			(at 3.199892 -2.800096)
			(size 0.3556 0.3556)
			(layers "F.Cu" "F.Mask" "F.Paste")
			(net "GND")
		)
		(pad "F1" smd circle
			(at -3.199892 -1.999996)
			(size 0.3556 0.3556)
			(layers "F.Cu" "F.Mask" "F.Paste")
			(net "GND")
		)
		(pad "F2" smd circle
			(at -2.400046 -1.999996)
			(size 0.3556 0.3556)
			(layers "F.Cu" "F.Mask" "F.Paste")
			(net "P1V2_STBY")
		)
		(pad "F3" smd circle
			(at -1.599946 -1.999996)
			(size 0.3556 0.3556)
			(layers "F.Cu" "F.Mask" "F.Paste")
			(net "MEMDQS_N0")
		)
		(pad "F7" smd circle
			(at 1.599946 -1.999996)
			(size 0.3556 0.3556)
			(layers "F.Cu" "F.Mask" "F.Paste")
			(net "MEMDQ_1")
		)
		(pad "F8" smd circle
			(at 2.400046 -1.999996)
			(size 0.3556 0.3556)
			(layers "F.Cu" "F.Mask" "F.Paste")
			(net "P1V2_STBY")
		)
		(pad "F9" smd circle
			(at 3.199892 -1.999996)
			(size 0.3556 0.3556)
			(layers "F.Cu" "F.Mask" "F.Paste")
			(net "PD_ZQ")
		)
		(pad "G1" smd circle
			(at -3.199892 -1.199896)
			(size 0.3556 0.3556)
			(layers "F.Cu" "F.Mask" "F.Paste")
			(net "P1V2_STBY")
		)
		(pad "G2" smd circle
			(at -2.400046 -1.199896)
			(size 0.3556 0.3556)
			(layers "F.Cu" "F.Mask" "F.Paste")
			(net "MEMDQ_0")
		)
		(pad "G3" smd circle
			(at -1.599946 -1.199896)
			(size 0.3556 0.3556)
			(layers "F.Cu" "F.Mask" "F.Paste")
			(net "MEMDQS_P0")
		)
		(pad "G7" smd circle
			(at 1.599946 -1.199896)
			(size 0.3556 0.3556)
			(layers "F.Cu" "F.Mask" "F.Paste")
			(net "P1V2_STBY")
		)
		(pad "G8" smd circle
			(at 2.400046 -1.199896)
			(size 0.3556 0.3556)
			(layers "F.Cu" "F.Mask" "F.Paste")
			(net "GND")
		)
		(pad "G9" smd circle
			(at 3.199892 -1.199896)
			(size 0.3556 0.3556)
			(layers "F.Cu" "F.Mask" "F.Paste")
			(net "P1V2_STBY")
		)
		(pad "H1" smd circle
			(at -3.199892 -0.40005)
			(size 0.3556 0.3556)
			(layers "F.Cu" "F.Mask" "F.Paste")
			(net "GND")
		)
		(pad "H2" smd circle
			(at -2.400046 -0.40005)
			(size 0.3556 0.3556)
			(layers "F.Cu" "F.Mask" "F.Paste")
			(net "MEMDQ_4")
		)
		(pad "H3" smd circle
			(at -1.599946 -0.40005)
			(size 0.3556 0.3556)
			(layers "F.Cu" "F.Mask" "F.Paste")
			(net "MEMDQ_2")
		)
		(pad "H7" smd circle
			(at 1.599946 -0.40005)
			(size 0.3556 0.3556)
			(layers "F.Cu" "F.Mask" "F.Paste")
			(net "MEMDQ_3")
		)
		(pad "H8" smd circle
			(at 2.400046 -0.40005)
			(size 0.3556 0.3556)
			(layers "F.Cu" "F.Mask" "F.Paste")
			(net "MEMDQ_5")
		)
		(pad "H9" smd circle
			(at 3.199892 -0.40005)
			(size 0.3556 0.3556)
			(layers "F.Cu" "F.Mask" "F.Paste")
			(net "GND")
		)
		(pad "J1" smd circle
			(at -3.199892 0.40005)
			(size 0.3556 0.3556)
			(layers "F.Cu" "F.Mask" "F.Paste")
			(net "P1V2_STBY")
		)
		(pad "J2" smd circle
			(at -2.400046 0.40005)
			(size 0.3556 0.3556)
			(layers "F.Cu" "F.Mask" "F.Paste")
			(net "P1V2_STBY")
		)
		(pad "J3" smd circle
			(at -1.599946 0.40005)
			(size 0.3556 0.3556)
			(layers "F.Cu" "F.Mask" "F.Paste")
			(net "MEMDQ_6")
		)
		(pad "J7" smd circle
			(at 1.599946 0.40005)
			(size 0.3556 0.3556)
			(layers "F.Cu" "F.Mask" "F.Paste")
			(net "MEMDQ_7")
		)
		(pad "J8" smd circle
			(at 2.400046 0.40005)
			(size 0.3556 0.3556)
			(layers "F.Cu" "F.Mask" "F.Paste")
			(net "P1V2_STBY")
		)
		(pad "J9" smd circle
			(at 3.199892 0.40005)
			(size 0.3556 0.3556)
			(layers "F.Cu" "F.Mask" "F.Paste")
			(net "P1V2_STBY")
		)
		(pad "K1" smd circle
			(at -3.199892 1.199896)
			(size 0.3556 0.3556)
			(layers "F.Cu" "F.Mask" "F.Paste")
			(net "GND")
		)
		(pad "K2" smd circle
			(at -2.400046 1.199896)
			(size 0.3556 0.3556)
			(layers "F.Cu" "F.Mask" "F.Paste")
			(net "MEMCKE")
		)
		(pad "K3" smd circle
			(at -1.599946 1.199896)
			(size 0.3556 0.3556)
			(layers "F.Cu" "F.Mask" "F.Paste")
			(net "MEMODT")
		)
		(pad "K7" smd circle
			(at 1.599946 1.199896)
			(size 0.3556 0.3556)
			(layers "F.Cu" "F.Mask" "F.Paste")
			(net "MEMCK_P")
		)
		(pad "K8" smd circle
			(at 2.400046 1.199896)
			(size 0.3556 0.3556)
			(layers "F.Cu" "F.Mask" "F.Paste")
			(net "MEMCK_N")
		)
		(pad "K9" smd circle
			(at 3.199892 1.199896)
			(size 0.3556 0.3556)
			(layers "F.Cu" "F.Mask" "F.Paste")
			(net "GND")
		)
		(pad "L1" smd circle
			(at -3.199892 1.999996)
			(size 0.3556 0.3556)
			(layers "F.Cu" "F.Mask" "F.Paste")
			(net "P1V2_STBY")
		)
		(pad "L2" smd circle
			(at -2.400046 1.999996)
			(size 0.3556 0.3556)
			(layers "F.Cu" "F.Mask" "F.Paste")
			(net "MEMWEN")
		)
		(pad "L3" smd circle
			(at -1.599946 1.999996)
			(size 0.3556 0.3556)
			(layers "F.Cu" "F.Mask" "F.Paste")
			(net "DDR4_ACT")
		)
		(pad "L7" smd circle
			(at 1.599946 1.999996)
			(size 0.3556 0.3556)
			(layers "F.Cu" "F.Mask" "F.Paste")
			(net "MEMCSN")
		)
		(pad "L8" smd circle
			(at 2.400046 1.999996)
			(size 0.3556 0.3556)
			(layers "F.Cu" "F.Mask" "F.Paste")
			(net "MEMRASN")
		)
		(pad "L9" smd circle
			(at 3.199892 1.999996)
			(size 0.3556 0.3556)
			(layers "F.Cu" "F.Mask" "F.Paste")
			(net "P1V2_STBY")
		)
		(pad "M1" smd circle
			(at -3.199892 2.800096)
			(size 0.3556 0.3556)
			(layers "F.Cu" "F.Mask" "F.Paste")
			(net "DDR_VREF")
		)
		(pad "M2" smd circle
			(at -2.400046 2.800096)
			(size 0.3556 0.3556)
			(layers "F.Cu" "F.Mask" "F.Paste")
			(net "MEMBG_0")
		)
		(pad "M3" smd circle
			(at -1.599946 2.800096)
			(size 0.3556 0.3556)
			(layers "F.Cu" "F.Mask" "F.Paste")
			(net "MEMA_10")
		)
		(pad "M7" smd circle
			(at 1.599946 2.800096)
			(size 0.3556 0.3556)
			(layers "F.Cu" "F.Mask" "F.Paste")
			(net "MEMA_12")
		)
		(pad "M8" smd circle
			(at 2.400046 2.800096)
			(size 0.3556 0.3556)
			(layers "F.Cu" "F.Mask" "F.Paste")
			(net "MEMCASN")
		)
		(pad "M9" smd circle
			(at 3.199892 2.800096)
			(size 0.3556 0.3556)
			(layers "F.Cu" "F.Mask" "F.Paste")
			(net "GND")
		)
		(pad "N1" smd circle
			(at -3.199892 3.599942)
			(size 0.3556 0.3556)
			(layers "F.Cu" "F.Mask" "F.Paste")
			(net "GND")
		)
		(pad "N2" smd circle
			(at -2.400046 3.599942)
			(size 0.3556 0.3556)
			(layers "F.Cu" "F.Mask" "F.Paste")
			(net "MEMBA_0")
		)
		(pad "N3" smd circle
			(at -1.599946 3.599942)
			(size 0.3556 0.3556)
			(layers "F.Cu" "F.Mask" "F.Paste")
			(net "MEMA_4")
		)
		(pad "N7" smd circle
			(at 1.599946 3.599942)
			(size 0.3556 0.3556)
			(layers "F.Cu" "F.Mask" "F.Paste")
			(net "MEMA_3")
		)
		(pad "N8" smd circle
			(at 2.400046 3.599942)
			(size 0.3556 0.3556)
			(layers "F.Cu" "F.Mask" "F.Paste")
			(net "MEMBA_1")
		)
		(pad "N9" smd circle
			(at 3.199892 3.599942)
			(size 0.3556 0.3556)
			(layers "F.Cu" "F.Mask" "F.Paste")
			(net "GND")
		)
		(pad "P1" smd circle
			(at -3.199892 4.400042)
			(size 0.3556 0.3556)
			(layers "F.Cu" "F.Mask" "F.Paste")
			(net "DDR4_RST_N")
		)
		(pad "P2" smd circle
			(at -2.400046 4.400042)
			(size 0.3556 0.3556)
			(layers "F.Cu" "F.Mask" "F.Paste")
			(net "MEMA_6")
		)
		(pad "P3" smd circle
			(at -1.599946 4.400042)
			(size 0.3556 0.3556)
			(layers "F.Cu" "F.Mask" "F.Paste")
			(net "MEMA_0")
		)
		(pad "P7" smd circle
			(at 1.599946 4.400042)
			(size 0.3556 0.3556)
			(layers "F.Cu" "F.Mask" "F.Paste")
			(net "MEMA_1")
		)
		(pad "P8" smd circle
			(at 2.400046 4.400042)
			(size 0.3556 0.3556)
			(layers "F.Cu" "F.Mask" "F.Paste")
			(net "MEMA_5")
		)
		(pad "P9" smd circle
			(at 3.199892 4.400042)
			(size 0.3556 0.3556)
			(layers "F.Cu" "F.Mask" "F.Paste")
			(net "DDR4_ALERT")
		)
		(pad "R1" smd circle
			(at -3.199892 5.199888)
			(size 0.3556 0.3556)
			(layers "F.Cu" "F.Mask" "F.Paste")
			(net "P1V2_STBY")
		)
		(pad "R2" smd circle
			(at -2.400046 5.199888)
			(size 0.3556 0.3556)
			(layers "F.Cu" "F.Mask" "F.Paste")
			(net "MEMA_8")
		)
		(pad "R3" smd circle
			(at -1.599946 5.199888)
			(size 0.3556 0.3556)
			(layers "F.Cu" "F.Mask" "F.Paste")
			(net "MEMA_2")
		)
		(pad "R7" smd circle
			(at 1.599946 5.199888)
			(size 0.3556 0.3556)
			(layers "F.Cu" "F.Mask" "F.Paste")
			(net "MEMA_9")
		)
		(pad "R8" smd circle
			(at 2.400046 5.199888)
			(size 0.3556 0.3556)
			(layers "F.Cu" "F.Mask" "F.Paste")
			(net "MEMA_7")
		)
		(pad "R9" smd circle
			(at 3.199892 5.199888)
			(size 0.3556 0.3556)
			(layers "F.Cu" "F.Mask" "F.Paste")
			(net "P2V5_STBY")
		)
		(pad "T1" smd circle
			(at -3.199892 5.999988)
			(size 0.3556 0.3556)
			(layers "F.Cu" "F.Mask" "F.Paste")
			(net "GND")
		)
		(pad "T2" smd circle
			(at -2.400046 5.999988)
			(size 0.3556 0.3556)
			(layers "F.Cu" "F.Mask" "F.Paste")
			(net "MEMA_11")
		)
		(pad "T3" smd circle
			(at -1.599946 5.999988)
			(size 0.3556 0.3556)
			(layers "F.Cu" "F.Mask" "F.Paste")
			(net "MEM_PAR")
		)
		(pad "T7" smd circle
			(at 1.599946 5.999988)
			(size 0.3556 0.3556)
			(layers "F.Cu" "F.Mask" "F.Paste")
			(net "Net_335")
		)
		(pad "T8" smd circle
			(at 2.400046 5.999988)
			(size 0.3556 0.3556)
			(layers "F.Cu" "F.Mask" "F.Paste")
			(net "MEMA_13")
		)
		(pad "T9" smd circle
			(at 3.199892 5.999988)
			(size 0.3556 0.3556)
			(layers "F.Cu" "F.Mask" "F.Paste")
			(net "P1V2_STBY")
		)
	)
)
